# S9S_MB_2U (Grand Teton) — schematic netlist excerpt (pin names and nets, part order shuffled) for the footprints in the layout excerpt that follows; sources: Cadence DE-HDL packaged netlist, KiCad conversion of 03242023_DA0F0TMBIJ0_F0T_Motherboard_J_brd_V01_OCP.brd

PC396  Q_CAP  2.2UF 10V 10% X6S  pkg C0402  page 289 : A = PVCCFA_EHV_FIVRA_CPU1_VDD2 ; B = GND
R3569  Q_RES  33.2 1% CHIP  pkg 0402LF  page 172 : A = SMB_INA230_3_3V3AUX_SDA_R ; B = SMB_INA230_3_3V3AUX_SDA_R1
C685  Q_CAP_DIFFBUS  DIFF BUS_0.22UF 6.3V 20% X6S  pkg C0201  page 177 : \1\ = P5E_CPU1_PE4_TX_C_DP<12> ; \2\ = P5E_CPU1_PE4_TX_DP<12>

(kicad_pcb
	(version 20260206)
	(generator "pcbnew")
	(generator_version "10.0")
	(general
		(thickness 1.6)
		(legacy_teardrops no)
	)
	(paper "A4")
	(title_block
		(title "03242023_DA0F0TMBIJ0_F0T_Motherboard_J_brd_V01_OCP.brd")
		(comment 1 "Grand Teton / footprints 1811-1813 of 6105")
	)
	(layers
		(0 "F.Cu" signal "TOP")
		(4 "In1.Cu" signal "GND")
		(6 "In2.Cu" signal "IN1")
		(8 "In3.Cu" signal "GND1")
		(10 "In4.Cu" signal "IN2")
		(12 "In5.Cu" signal "GND2")
		(14 "In6.Cu" signal "IN3")
		(16 "In7.Cu" signal "GND3")
		(18 "In8.Cu" signal "VCC")
		(20 "In9.Cu" signal "VCC1")
		(22 "In10.Cu" signal "GND4")
		(24 "In11.Cu" signal "IN4")
		(26 "In12.Cu" signal "GND5")
		(28 "In13.Cu" signal "IN5")
		(30 "In14.Cu" signal "GND6")
		(32 "In15.Cu" signal "IN6")
		(34 "In16.Cu" signal "GND7")
		(2 "B.Cu" signal "BOTTOM")
		(9 "F.Adhes" user "F.Adhesive")
		(11 "B.Adhes" user "B.Adhesive")
		(13 "F.Paste" user "Package Geometry/Pastemask Top")
		(15 "B.Paste" user "Package Geometry/Pastemask Bottom")
		(5 "F.SilkS" user "Ref Des/Silkscreen Top")
		(7 "B.SilkS" user "Ref Des/Silkscreen Bottom")
		(1 "F.Mask" user "Board Geometry/Soldermask Top")
		(3 "B.Mask" user "Board Geometry/Soldermask Bottom")
		(17 "Dwgs.User" user "User.Drawings")
		(19 "Cmts.User" user "User.Comments")
		(21 "Eco1.User" user "User.Eco1")
		(23 "Eco2.User" user "User.Eco2")
		(25 "Edge.Cuts" user "Board Geometry/Outline")
		(27 "Margin" user)
		(31 "F.CrtYd" user "Package Geometry/Place Bound Top")
		(29 "B.CrtYd" user "Package Geometry/Place Bound Bottom")
		(35 "F.Fab" user "Ref Des/Assembly Top")
		(33 "B.Fab" user "Ref Des/Assembly Bottom")
	)
	(footprint ""
		(layer "F.Cu")
		(at 47.678594 -356.02418 90)
		(property "Reference" "PC396"
			(at 0 0 90)
			(layer "F.SilkS")
			(hide yes)
			(effects
				(font
					(size 1.27 1.27)
				)
			)
		)
		(property "Value" ""
			(at 0 0 90)
			(layer "F.Fab")
			(effects
				(font
					(size 1.27 1.27)
				)
			)
		)
		(duplicate_pad_numbers_are_jumpers no)
		(fp_line
			(start 0.7874 -0.4064)
			(end 0.7874 0.4064)
			(stroke
				(width 0.1524)
				(type default)
			)
			(layer "F.SilkS")
		)
		(fp_line
			(start -0.7874 -0.4064)
			(end 0.7874 -0.4064)
			(stroke
				(width 0.1524)
				(type default)
			)
			(layer "F.SilkS")
		)
		(fp_line
			(start 0.7874 0.4064)
			(end -0.7874 0.4064)
			(stroke
				(width 0.1524)
				(type default)
			)
			(layer "F.SilkS")
		)
		(fp_line
			(start -0.7874 0.4064)
			(end -0.7874 -0.4064)
			(stroke
				(width 0.1524)
				(type default)
			)
			(layer "F.SilkS")
		)
		(fp_line
			(start -0.12065 -0.305054)
			(end -0.12065 -0.2794)
			(stroke
				(width 0.1)
				(type default)
			)
			(layer "F.Fab")
		)
		(fp_line
			(start -0.67945 -0.305054)
			(end -0.12065 -0.305054)
			(stroke
				(width 0.1)
				(type default)
			)
			(layer "F.Fab")
		)
		(fp_line
			(start 0.67945 -0.3048)
			(end 0.67945 0.3048)
			(stroke
				(width 0.1)
				(type default)
			)
			(layer "F.Fab")
		)
		(fp_line
			(start 0.12065 -0.3048)
			(end 0.67945 -0.3048)
			(stroke
				(width 0.1)
				(type default)
			)
			(layer "F.Fab")
		)
		(fp_line
			(start 0.12065 -0.2794)
			(end 0.12065 -0.3048)
			(stroke
				(width 0.1)
				(type default)
			)
			(layer "F.Fab")
		)
		(fp_line
			(start -0.12065 -0.2794)
			(end 0.12065 -0.2794)
			(stroke
				(width 0.1)
				(type default)
			)
			(layer "F.Fab")
		)
		(fp_line
			(start 0.120396 0.2794)
			(end -0.12065 0.2794)
			(stroke
				(width 0.1)
				(type default)
			)
			(layer "F.Fab")
		)
		(fp_line
			(start -0.12065 0.2794)
			(end -0.12065 0.3048)
			(stroke
				(width 0.1)
				(type default)
			)
			(layer "F.Fab")
		)
		(fp_line
			(start 0.67945 0.3048)
			(end 0.120396 0.3048)
			(stroke
				(width 0.1)
				(type default)
			)
			(layer "F.Fab")
		)
		(fp_line
			(start 0.120396 0.3048)
			(end 0.120396 0.2794)
			(stroke
				(width 0.1)
				(type default)
			)
			(layer "F.Fab")
		)
		(fp_line
			(start -0.12065 0.3048)
			(end -0.67945 0.3048)
			(stroke
				(width 0.1)
				(type default)
			)
			(layer "F.Fab")
		)
		(fp_line
			(start -0.67945 0.3048)
			(end -0.67945 -0.305054)
			(stroke
				(width 0.1)
				(type default)
			)
			(layer "F.Fab")
		)
		(pad "1" smd circle
			(at -0.40005 0 90)
			(size 0 0)
			(layers "F.Cu" "F.Mask" "F.Paste")
			(net "PVCCFA_EHV_FIVRA_CPU1_VDD2")
		)
		(pad "2" smd circle
			(at 0.40005 0 90)
			(size 0 0)
			(layers "F.Cu" "F.Mask" "F.Paste")
			(net "GND")
		)
	)
	(footprint ""
		(layer "F.Cu")
		(at 70.7136 -34.788348)
		(property "Reference" "R3569"
			(at 0 0 0)
			(layer "F.SilkS")
			(hide yes)
			(effects
				(font
					(size 1.27 1.27)
				)
			)
		)
		(property "Value" ""
			(at 0 0 0)
			(layer "F.Fab")
			(effects
				(font
					(size 1.27 1.27)
				)
			)
		)
		(duplicate_pad_numbers_are_jumpers no)
		(fp_line
			(start -0.7874 -0.4064)
			(end 0.7874 -0.4064)
			(stroke
				(width 0.1524)
				(type default)
			)
			(layer "F.SilkS")
		)
		(fp_line
			(start -0.7874 0.4064)
			(end -0.7874 -0.4064)
			(stroke
				(width 0.1524)
				(type default)
			)
			(layer "F.SilkS")
		)
		(fp_line
			(start 0.7874 -0.4064)
			(end 0.7874 0.4064)
			(stroke
				(width 0.1524)
				(type default)
			)
			(layer "F.SilkS")
		)
		(fp_line
			(start 0.7874 0.4064)
			(end -0.7874 0.4064)
			(stroke
				(width 0.1524)
				(type default)
			)
			(layer "F.SilkS")
		)
		(fp_line
			(start -0.67945 -0.305054)
			(end -0.12065 -0.305054)
			(stroke
				(width 0.1)
				(type default)
			)
			(layer "F.Fab")
		)
		(fp_line
			(start -0.67945 0.3048)
			(end -0.67945 -0.305054)
			(stroke
				(width 0.1)
				(type default)
			)
			(layer "F.Fab")
		)
		(fp_line
			(start -0.12065 -0.305054)
			(end -0.12065 -0.2794)
			(stroke
				(width 0.1)
				(type default)
			)
			(layer "F.Fab")
		)
		(fp_line
			(start -0.12065 -0.2794)
			(end 0.12065 -0.2794)
			(stroke
				(width 0.1)
				(type default)
			)
			(layer "F.Fab")
		)
		(fp_line
			(start -0.12065 0.2794)
			(end -0.12065 0.3048)
			(stroke
				(width 0.1)
				(type default)
			)
			(layer "F.Fab")
		)
		(fp_line
			(start -0.12065 0.3048)
			(end -0.67945 0.3048)
			(stroke
				(width 0.1)
				(type default)
			)
			(layer "F.Fab")
		)
		(fp_line
			(start 0.120396 0.2794)
			(end -0.12065 0.2794)
			(stroke
				(width 0.1)
				(type default)
			)
			(layer "F.Fab")
		)
		(fp_line
			(start 0.120396 0.3048)
			(end 0.120396 0.2794)
			(stroke
				(width 0.1)
				(type default)
			)
			(layer "F.Fab")
		)
		(fp_line
			(start 0.12065 -0.3048)
			(end 0.67945 -0.3048)
			(stroke
				(width 0.1)
				(type default)
			)
			(layer "F.Fab")
		)
		(fp_line
			(start 0.12065 -0.2794)
			(end 0.12065 -0.3048)
			(stroke
				(width 0.1)
				(type default)
			)
			(layer "F.Fab")
		)
		(fp_line
			(start 0.67945 -0.3048)
			(end 0.67945 0.3048)
			(stroke
				(width 0.1)
				(type default)
			)
			(layer "F.Fab")
		)
		(fp_line
			(start 0.67945 0.3048)
			(end 0.120396 0.3048)
			(stroke
				(width 0.1)
				(type default)
			)
			(layer "F.Fab")
		)
		(pad "1" smd circle
			(at -0.40005 0)
			(size 0 0)
			(layers "F.Cu" "F.Mask" "F.Paste")
			(net "SMB_INA230_3_3V3AUX_SDA_R")
		)
		(pad "2" smd circle
			(at 0.40005 0)
			(size 0 0)
			(layers "F.Cu" "F.Mask" "F.Paste")
			(net "SMB_INA230_3_3V3AUX_SDA_R1")
		)
	)
	(footprint ""
		(layer "F.Cu")
		(at 86.973918 -408.517344 -90)
		(property "Reference" "C685"
			(at 0 0 270)
			(layer "F.SilkS")
			(hide yes)
			(effects
				(font
					(size 1.27 1.27)
				)
			)
		)
		(property "Value" ""
			(at 0 0 270)
			(layer "F.Fab")
			(effects
				(font
					(size 1.27 1.27)
				)
			)
		)
		(duplicate_pad_numbers_are_jumpers no)
		(fp_line
			(start -0.299974 0.150114)
			(end -0.299974 -0.150114)
			(stroke
				(width 0.1)
				(type default)
			)
			(layer "F.Fab")
		)
		(fp_line
			(start 0.299974 0.150114)
			(end -0.299974 0.150114)
			(stroke
				(width 0.1)
				(type default)
			)
			(layer "F.Fab")
		)
		(fp_line
			(start -0.299974 -0.150114)
			(end 0.299974 -0.150114)
			(stroke
				(width 0.1)
				(type default)
			)
			(layer "F.Fab")
		)
		(fp_line
			(start 0.299974 -0.150114)
			(end 0.299974 0.150114)
			(stroke
				(width 0.1)
				(type default)
			)
			(layer "F.Fab")
		)
		(pad "1" smd rect
			(at -0.2667 0 270)
			(size 0.3048 0.381)
			(layers "F.Cu" "F.Mask" "F.Paste")
			(net "P5E_CPU1_PE4_TX_C_DP<12>")
		)
		(pad "2" smd rect
			(at 0.2667 0 270)
			(size 0.3048 0.381)
			(layers "F.Cu" "F.Mask" "F.Paste")
			(net "P5E_CPU1_PE4_TX_DP<12>")
		)
	)
)
